#ISCELL
  mstr_misc dns *
  *
#ISCELL
  pure_quanta quanta_title_block_c *
  *
#ISCELL
  pure_quanta_power cad_note *
  *
#CELL
  pure_quanta q_res *
  page337_i1
#ISCELL
  standard offpage *
  page337_i10
#CELL
  pure_quanta q_res *
  page337_i11
#CELL
  pure_quanta q_res *
  page337_i12
#ISCELL
  pure_quanta_power universal_power *
  page337_i13
#ISCELL
  standard offpage *
  page337_i14
#ISCELL
  pure_quanta_power universal_gnd *
  page337_i15
#CELL
  pure_quanta pi6cv304le *
  page337_i16
#ISCELL
  pure_quanta_power universal_power *
  page337_i17
#ISCELL
  pure_quanta_power universal_gnd *
  page337_i18
#CELL
  pure_quanta q_cap *
  page337_i19
#ISCELL
  pure_quanta_power universal_gnd *
  page337_i2
#CELL
  pure_quanta q_res *
  page337_i20
#CELL
  pure_quanta q_res *
  page337_i21
#CELL
  pure_quanta q_res *
  page337_i22
#ISCELL
  standard offpage *
  page337_i23
#ISCELL
  pure_quanta_power universal_gnd *
  page337_i24
#CELL
  pure_quanta 74lvc1g07gv *
  page337_i25
#ISCELL
  standard offpage *
  page337_i26
#ISCELL
  standard offpage *
  page337_i27
#ISCELL
  standard offpage *
  page337_i28
#CELL
  pure_quanta q_res *
  page337_i29
#CELL
  pure_quanta q_cap *
  page337_i3
#ISCELL
  standard offpage *
  page337_i30
#CELL
  pure_quanta q_res *
  page337_i31
#ISCELL
  pure_quanta_power universal_gnd *
  page337_i32
#CELL
  pure_quanta q_cap *
  page337_i33
#ISCELL
  pure_quanta_power universal_power *
  page337_i34
#CELL
  pure_quanta q_res *
  page337_i35
#ISCELL
  pure_quanta_power universal_power *
  page337_i36
#ISCELL
  pure_quanta_power universal_gnd *
  page337_i37
#CELL
  pure_quanta 74lvc1g07gv *
  page337_i38
#ISCELL
  pure_quanta_power universal_gnd *
  page337_i39
#CELL
  pure_quanta q_osc4p *
  page337_i4
#CELL
  pure_quanta q_cap *
  page337_i40
#ISCELL
  pure_quanta_power universal_power *
  page337_i41
#CELL
  pure_quanta q_res *
  page337_i42
#ISCELL
  pure_quanta_power universal_power *
  page337_i43
#CELL
  pure_quanta q_res *
  page337_i44
#ISCELL
  pure_quanta_power universal_power *
  page337_i45
#ISCELL
  pure_quanta_power universal_gnd *
  page337_i46
#CELL
  pure_quanta q_cap *
  page337_i47
#ISCELL
  standard offpage *
  page337_i48
#ISCELL
  pure_quanta_power universal_gnd *
  page337_i49
#ISCELL
  pure_quanta_power universal_power *
  page337_i5
#CELL
  pure_quanta q_res *
  page337_i50
#ISCELL
  standard offpage *
  page337_i51
#ISCELL
  pure_quanta_power universal_gnd *
  page337_i52
#CELL
  pure_quanta q_cap *
  page337_i53
#ISCELL
  pure_quanta_power universal_power *
  page337_i54
#ISCELL
  standard offpage *
  page337_i55
#CELL
  pure_quanta q_res *
  page337_i56
#ISCELL
  pure_quanta_power universal_power *
  page337_i57
#ISCELL
  standard offpage *
  page337_i59
#ISCELL
  pure_quanta_power universal_gnd *
  page337_i6
#ISCELL
  pure_quanta_power universal_gnd *
  page337_i60
#CELL
  pure_quanta q_cap *
  page337_i61
#ISCELL
  pure_quanta_power universal_gnd *
  page337_i62
#ISCELL
  pure_quanta_power universal_power *
  page337_i63
#CELL
  pure_quanta 74lvc1g17gw *
  page337_i64
#CELL
  pure_quanta q_res *
  page337_i7
#ISCELL
  standard offpage *
  page337_i74
#ISCELL
  standard offpage *
  page337_i75
#ISCELL
  standard offpage *
  page337_i76
#ISCELL
  standard offpage *
  page337_i77
#CELL
  pure_quanta q_res *
  page337_i78
#CELL
  pure_quanta q_res *
  page337_i79
#CELL
  pure_quanta 74lvc1g126se7 *
  page337_i8
#CELL
  pure_quanta q_res *
  page337_i80
#CELL
  pure_quanta q_res *
  page337_i81
#CELL
  pure_quanta 74lvc1g66gv *
  page337_i82
#ISCELL
  pure_quanta_power universal_gnd *
  page337_i9
